(kicad_pcb
	(version 20241229)
	(generator "pcbnew")
	(generator_version "9.0")
	(general
		(thickness 1.62)
		(legacy_teardrops no)
	)
	(paper "A4")
	(title_block
		(title "OCuLink to 10GbE adapter")
		(date "2026-02-23")
		(rev "1.1.0")
		(company "Antmicro Ltd")
		(comment 1 "www.antmicro.com")
		(comment 9 "footprints 397-402 of 510")
	)
	(layers
		(0 "F.Cu" signal)
		(4 "In1.Cu" signal)
		(6 "In2.Cu" signal)
		(8 "In3.Cu" signal)
		(10 "In4.Cu" signal)
		(12 "In5.Cu" signal)
		(14 "In6.Cu" signal)
		(2 "B.Cu" signal)
		(9 "F.Adhes" user "F.Adhesive")
		(11 "B.Adhes" user "B.Adhesive")
		(13 "F.Paste" user)
		(15 "B.Paste" user)
		(5 "F.SilkS" user "F.Silkscreen")
		(7 "B.SilkS" user "B.Silkscreen")
		(1 "F.Mask" user)
		(3 "B.Mask" user)
		(17 "Dwgs.User" user "User.Drawings")
		(19 "Cmts.User" user "User.Comments")
		(21 "Eco1.User" user "User.Eco1")
		(23 "Eco2.User" user "User.Eco2")
		(25 "Edge.Cuts" user)
		(27 "Margin" user)
		(31 "F.CrtYd" user "F.Courtyard")
		(29 "B.CrtYd" user "B.Courtyard")
		(35 "F.Fab" user)
		(33 "B.Fab" user)
	)
	(footprint "antmicro-footprints:R_0402_1005Metric"
		(layer "B.Cu")
		(at 74.480001 145.34 90)
		(descr "Resistor SMD 0402")
		(tags "resistor SMD 0402")
		(property "Reference" "R37"
			(at 0.77 -0.310001 90)
			(layer "B.SilkS")
			(effects
				(font
					(size 0.7 0.7)
					(thickness 0.15)
				)
				(justify right top mirror)
			)
		)
		(property "Value" "R_220R_0402"
			(at -1.011843 -1.772046 90)
			(layer "B.Fab")
			(hide yes)
			(effects
				(font
					(size 0.7 0.7)
					(thickness 0.15)
				)
				(justify right top mirror)
			)
		)
		(property "Datasheet" "https://www.bourns.com/docs/product-datasheets/cr.pdf"
			(at 0 0 90)
			(layer "B.Fab")
			(hide yes)
			(effects
				(font
					(size 1.27 1.27)
					(thickness 0.15)
				)
				(justify mirror)
			)
		)
		(property "Description" "SMD Chip Resistor, 220 ohm, ± 1%, 62.5 mW, 0402 [1005 Metric], Thick Film, General Purpose"
			(at 0 0 90)
			(layer "B.Fab")
			(hide yes)
			(effects
				(font
					(size 1.27 1.27)
					(thickness 0.15)
				)
				(justify mirror)
			)
		)
		(property "MPN" "CR0402-FX-2200GLF"
			(at 0 0 90)
			(unlocked yes)
			(layer "B.Fab")
			(hide yes)
			(effects
				(font
					(size 1 1)
					(thickness 0.15)
				)
				(justify mirror)
			)
		)
		(property "Manufacturer" "Bourns"
			(at 0 0 90)
			(unlocked yes)
			(layer "B.Fab")
			(hide yes)
			(effects
				(font
					(size 1 1)
					(thickness 0.15)
				)
				(justify mirror)
			)
		)
		(property "License" "Apache-2.0"
			(at 0 0 90)
			(unlocked yes)
			(layer "B.Fab")
			(hide yes)
			(effects
				(font
					(size 1 1)
					(thickness 0.15)
				)
				(justify mirror)
			)
		)
		(property "Author" "Antmicro"
			(at 0 0 90)
			(unlocked yes)
			(layer "B.Fab")
			(hide yes)
			(effects
				(font
					(size 1 1)
					(thickness 0.15)
				)
				(justify mirror)
			)
		)
		(property "Val" "220R"
			(at 0 0 90)
			(unlocked yes)
			(layer "B.Fab")
			(hide yes)
			(effects
				(font
					(size 1 1)
					(thickness 0.15)
				)
				(justify mirror)
			)
		)
		(property "Tolerance" "1%"
			(at 0 0 90)
			(unlocked yes)
			(layer "B.Fab")
			(hide yes)
			(effects
				(font
					(size 1 1)
					(thickness 0.15)
				)
				(justify mirror)
			)
		)
		(sheetname "/2xRJ45/")
		(sheetfile "2xrj45.kicad_sch")
		(attr smd)
		(fp_rect
			(start -0.925 0.47)
			(end 0.925 -0.47)
			(stroke
				(width 0.05)
				(type default)
			)
			(fill no)
			(layer "B.CrtYd")
		)
		(fp_rect
			(start -0.5 0.25)
			(end 0.5 -0.25)
			(stroke
				(width 0.15)
				(type solid)
			)
			(fill no)
			(layer "B.Fab")
		)
		(pad "1" smd roundrect
			(at -0.48 0 90)
			(size 0.59 0.64)
			(layers "B.Cu" "B.Mask" "B.Paste")
			(roundrect_rratio 0.25)
			(net 53 "Net-(J3-LED_YG_G-)")
			(pintype "passive")
		)
		(pad "2" smd roundrect
			(at 0.48 0 90)
			(size 0.59 0.64)
			(layers "B.Cu" "B.Mask" "B.Paste")
			(roundrect_rratio 0.25)
			(net 81 "/2xRJ45/~{P0_LED_LINK_10G}")
			(pintype "passive")
		)
	)
	(footprint "antmicro-footprints:TP_SMD_1mm"
		(layer "B.Cu")
		(at 77.99 72.3 -90)
		(property "Reference" "TP27"
			(at -1.81 5.81 90)
			(layer "B.SilkS")
			(effects
				(font
					(size 0.7 0.7)
					(thickness 0.15)
				)
				(justify left bottom mirror)
			)
		)
		(property "Value" "TP_1mm_SMD"
			(at 0 -1.4 90)
			(layer "B.Fab")
			(hide yes)
			(effects
				(font
					(size 0.7 0.7)
					(thickness 0.15)
				)
				(justify left bottom mirror)
			)
		)
		(property "Description" "Test point 1mm SMD"
			(at 0 0 90)
			(layer "B.Fab")
			(hide yes)
			(effects
				(font
					(size 1.27 1.27)
					(thickness 0.15)
				)
				(justify mirror)
			)
		)
		(property "MPN" ""
			(at 0 0 90)
			(unlocked yes)
			(layer "B.Fab")
			(hide yes)
			(effects
				(font
					(size 1 1)
					(thickness 0.15)
				)
				(justify mirror)
			)
		)
		(property "Manufacturer" ""
			(at 0 0 90)
			(unlocked yes)
			(layer "B.Fab")
			(hide yes)
			(effects
				(font
					(size 1 1)
					(thickness 0.15)
				)
				(justify mirror)
			)
		)
		(property "Author" "Antmicro"
			(at 0 0 90)
			(unlocked yes)
			(layer "B.Fab")
			(hide yes)
			(effects
				(font
					(size 1 1)
					(thickness 0.15)
				)
				(justify mirror)
			)
		)
		(property "License" "Apache-2.0"
			(at 0 0 90)
			(unlocked yes)
			(layer "B.Fab")
			(hide yes)
			(effects
				(font
					(size 1 1)
					(thickness 0.15)
				)
				(justify mirror)
			)
		)
		(sheetname "/Power/")
		(sheetfile "power.kicad_sch")
		(attr exclude_from_pos_files exclude_from_bom)
		(fp_circle
			(center 0 0)
			(end 0.6 0)
			(stroke
				(width 0.05)
				(type default)
			)
			(fill no)
			(layer "B.CrtYd")
		)
		(pad "1" smd circle
			(at 0 0 270)
			(size 1 1)
			(layers "B.Cu" "B.Mask")
			(net 350 "/Power/+12V_IN")
			(pinfunction "1")
			(pintype "passive")
		)
	)
	(footprint "antmicro-footprints:R_0402_1005Metric"
		(layer "B.Cu")
		(at 89.725 103.45)
		(descr "Resistor SMD 0402")
		(tags "resistor SMD 0402")
		(property "Reference" "R119"
			(at -1.695 0.58 0)
			(layer "B.SilkS")
			(effects
				(font
					(size 0.7 0.7)
					(thickness 0.15)
				)
				(justify right top mirror)
			)
		)
		(property "Value" "R_1k_0402"
			(at -1.011843 -1.772046 0)
			(layer "B.Fab")
			(hide yes)
			(effects
				(font
					(size 0.7 0.7)
					(thickness 0.15)
				)
				(justify right top mirror)
			)
		)
		(property "Datasheet" "https://www.bourns.com/docs/product-datasheets/cr.pdf"
			(at 0 0 0)
			(layer "B.Fab")
			(hide yes)
			(effects
				(font
					(size 1.27 1.27)
					(thickness 0.15)
				)
				(justify mirror)
			)
		)
		(property "Description" "SMD Chip Resistor, 1 kohm, ± 1%, 63 mW, 0402 [1005 Metric], Thick Film, General Purpose"
			(at 0 0 0)
			(layer "B.Fab")
			(hide yes)
			(effects
				(font
					(size 1.27 1.27)
					(thickness 0.15)
				)
				(justify mirror)
			)
		)
		(property "MPN" "CR0402-FX-1001GLF"
			(at 0 0 0)
			(unlocked yes)
			(layer "B.Fab")
			(hide yes)
			(effects
				(font
					(size 1 1)
					(thickness 0.15)
				)
				(justify mirror)
			)
		)
		(property "Manufacturer" "Bourns"
			(at 0 0 0)
			(unlocked yes)
			(layer "B.Fab")
			(hide yes)
			(effects
				(font
					(size 1 1)
					(thickness 0.15)
				)
				(justify mirror)
			)
		)
		(property "License" "Apache-2.0"
			(at 0 0 0)
			(unlocked yes)
			(layer "B.Fab")
			(hide yes)
			(effects
				(font
					(size 1 1)
					(thickness 0.15)
				)
				(justify mirror)
			)
		)
		(property "Author" "Antmicro"
			(at 0 0 0)
			(unlocked yes)
			(layer "B.Fab")
			(hide yes)
			(effects
				(font
					(size 1 1)
					(thickness 0.15)
				)
				(justify mirror)
			)
		)
		(property "Val" "1k"
			(at 0 0 0)
			(unlocked yes)
			(layer "B.Fab")
			(hide yes)
			(effects
				(font
					(size 1 1)
					(thickness 0.15)
				)
				(justify mirror)
			)
		)
		(property "Tolerance" "1%"
			(at 0 0 0)
			(unlocked yes)
			(layer "B.Fab")
			(hide yes)
			(effects
				(font
					(size 1 1)
					(thickness 0.15)
				)
				(justify mirror)
			)
		)
		(sheetname "/X710-AT2 Misc/")
		(sheetfile "x710-at2-mics.kicad_sch")
		(attr smd)
		(fp_rect
			(start -0.925 0.47)
			(end 0.925 -0.47)
			(stroke
				(width 0.05)
				(type default)
			)
			(fill no)
			(layer "B.CrtYd")
		)
		(fp_rect
			(start -0.5 0.25)
			(end 0.5 -0.25)
			(stroke
				(width 0.15)
				(type solid)
			)
			(fill no)
			(layer "B.Fab")
		)
		(pad "1" smd roundrect
			(at -0.48 0)
			(size 0.59 0.64)
			(layers "B.Cu" "B.Mask" "B.Paste")
			(roundrect_rratio 0.25)
			(net 28 "GND")
			(pintype "passive")
		)
		(pad "2" smd roundrect
			(at 0.48 0)
			(size 0.59 0.64)
			(layers "B.Cu" "B.Mask" "B.Paste")
			(roundrect_rratio 0.25)
			(net 115 "/X710-AT2 Misc/RSVD_J11_VSS")
			(pintype "passive")
		)
	)
	(footprint "antmicro-footprints:R_0402_1005Metric"
		(layer "B.Cu")
		(at 107.2 70.25 -90)
		(descr "Resistor SMD 0402")
		(tags "resistor SMD 0402")
		(property "Reference" "R93"
			(at 0.9 -0.48 90)
			(layer "B.SilkS")
			(effects
				(font
					(size 0.7 0.7)
					(thickness 0.15)
				)
				(justify left bottom mirror)
			)
		)
		(property "Value" "R_10k_0402"
			(at -1.011843 -1.772046 90)
			(layer "B.Fab")
			(hide yes)
			(effects
				(font
					(size 0.7 0.7)
					(thickness 0.15)
				)
				(justify left bottom mirror)
			)
		)
		(property "Datasheet" "https://www.bourns.com/docs/product-datasheets/cr.pdf"
			(at 0 0 90)
			(layer "B.Fab")
			(hide yes)
			(effects
				(font
					(size 1.27 1.27)
					(thickness 0.15)
				)
				(justify mirror)
			)
		)
		(property "Description" "SMD Chip Resistor, 10 kohm, ± 1%, 62.5 mW, 0402 [1005 Metric], Thick Film, General Purpose"
			(at 0 0 90)
			(layer "B.Fab")
			(hide yes)
			(effects
				(font
					(size 1.27 1.27)
					(thickness 0.15)
				)
				(justify mirror)
			)
		)
		(property "MPN" "CR0402-FX-1002GLF"
			(at 0 0 270)
			(unlocked yes)
			(layer "B.Fab")
			(hide yes)
			(effects
				(font
					(size 1 1)
					(thickness 0.15)
				)
				(justify mirror)
			)
		)
		(property "Manufacturer" "Bourns"
			(at 0 0 270)
			(unlocked yes)
			(layer "B.Fab")
			(hide yes)
			(effects
				(font
					(size 1 1)
					(thickness 0.15)
				)
				(justify mirror)
			)
		)
		(property "License" "Apache-2.0"
			(at 0 0 270)
			(unlocked yes)
			(layer "B.Fab")
			(hide yes)
			(effects
				(font
					(size 1 1)
					(thickness 0.15)
				)
				(justify mirror)
			)
		)
		(property "Author" "Antmicro"
			(at 0 0 270)
			(unlocked yes)
			(layer "B.Fab")
			(hide yes)
			(effects
				(font
					(size 1 1)
					(thickness 0.15)
				)
				(justify mirror)
			)
		)
		(property "Val" "10k"
			(at 0 0 270)
			(unlocked yes)
			(layer "B.Fab")
			(hide yes)
			(effects
				(font
					(size 1 1)
					(thickness 0.15)
				)
				(justify mirror)
			)
		)
		(property "Tolerance" "1%"
			(at 0 0 270)
			(unlocked yes)
			(layer "B.Fab")
			(hide yes)
			(effects
				(font
					(size 1 1)
					(thickness 0.15)
				)
				(justify mirror)
			)
		)
		(sheetname "/X710-AT2 Misc/")
		(sheetfile "x710-at2-mics.kicad_sch")
		(attr smd)
		(fp_rect
			(start -0.925 0.47)
			(end 0.925 -0.47)
			(stroke
				(width 0.05)
				(type default)
			)
			(fill no)
			(layer "B.CrtYd")
		)
		(fp_rect
			(start -0.5 0.25)
			(end 0.5 -0.25)
			(stroke
				(width 0.15)
				(type solid)
			)
			(fill no)
			(layer "B.Fab")
		)
		(pad "1" smd roundrect
			(at -0.48 0 270)
			(size 0.59 0.64)
			(layers "B.Cu" "B.Mask" "B.Paste")
			(roundrect_rratio 0.25)
			(net 395 "/OCuLink/SMBus.SDA")
			(pintype "passive")
		)
		(pad "2" smd roundrect
			(at 0.48 0 270)
			(size 0.59 0.64)
			(layers "B.Cu" "B.Mask" "B.Paste")
			(roundrect_rratio 0.25)
			(net 7 "+3V3")
			(pintype "passive")
		)
	)
	(footprint "antmicro-footprints:R_0402_1005Metric"
		(layer "B.Cu")
		(at 109.5 68.6 180)
		(descr "Resistor SMD 0402")
		(tags "resistor SMD 0402")
		(property "Reference" "R165"
			(at -1.44 5.61 0)
			(layer "B.SilkS")
			(effects
				(font
					(size 0.7 0.7)
					(thickness 0.15)
				)
				(justify left bottom mirror)
			)
		)
		(property "Value" "R_10k_0402"
			(at -1.011843 -1.772046 0)
			(layer "B.Fab")
			(hide yes)
			(effects
				(font
					(size 0.7 0.7)
					(thickness 0.15)
				)
				(justify left bottom mirror)
			)
		)
		(property "Datasheet" "https://www.bourns.com/docs/product-datasheets/cr.pdf"
			(at 0 0 0)
			(layer "B.Fab")
			(hide yes)
			(effects
				(font
					(size 1.27 1.27)
					(thickness 0.15)
				)
				(justify mirror)
			)
		)
		(property "Description" "SMD Chip Resistor, 10 kohm, ± 1%, 62.5 mW, 0402 [1005 Metric], Thick Film, General Purpose"
			(at 0 0 0)
			(layer "B.Fab")
			(hide yes)
			(effects
				(font
					(size 1.27 1.27)
					(thickness 0.15)
				)
				(justify mirror)
			)
		)
		(property "MPN" "CR0402-FX-1002GLF"
			(at 0 0 180)
			(unlocked yes)
			(layer "B.Fab")
			(hide yes)
			(effects
				(font
					(size 1 1)
					(thickness 0.15)
				)
				(justify mirror)
			)
		)
		(property "Manufacturer" "Bourns"
			(at 0 0 180)
			(unlocked yes)
			(layer "B.Fab")
			(hide yes)
			(effects
				(font
					(size 1 1)
					(thickness 0.15)
				)
				(justify mirror)
			)
		)
		(property "License" "Apache-2.0"
			(at 0 0 180)
			(unlocked yes)
			(layer "B.Fab")
			(hide yes)
			(effects
				(font
					(size 1 1)
					(thickness 0.15)
				)
				(justify mirror)
			)
		)
		(property "Author" "Antmicro"
			(at 0 0 180)
			(unlocked yes)
			(layer "B.Fab")
			(hide yes)
			(effects
				(font
					(size 1 1)
					(thickness 0.15)
				)
				(justify mirror)
			)
		)
		(property "Val" "10k"
			(at 0 0 180)
			(unlocked yes)
			(layer "B.Fab")
			(hide yes)
			(effects
				(font
					(size 1 1)
					(thickness 0.15)
				)
				(justify mirror)
			)
		)
		(property "Tolerance" "1%"
			(at 0 0 180)
			(unlocked yes)
			(layer "B.Fab")
			(hide yes)
			(effects
				(font
					(size 1 1)
					(thickness 0.15)
				)
				(justify mirror)
			)
		)
		(sheetname "/OCuLink/")
		(sheetfile "oculink.kicad_sch")
		(attr smd exclude_from_pos_files exclude_from_bom dnp)
		(fp_rect
			(start -0.925 0.47)
			(end 0.925 -0.47)
			(stroke
				(width 0.05)
				(type default)
			)
			(fill no)
			(layer "B.CrtYd")
		)
		(fp_rect
			(start -0.5 0.25)
			(end 0.5 -0.25)
			(stroke
				(width 0.15)
				(type solid)
			)
			(fill no)
			(layer "B.Fab")
		)
		(pad "1" smd roundrect
			(at -0.48 0 180)
			(size 0.59 0.64)
			(layers "B.Cu" "B.Mask" "B.Paste")
			(roundrect_rratio 0.25)
			(net 321 "/OCuLink/~{CPRSNT}_R")
			(pintype "passive")
		)
		(pad "2" smd roundrect
			(at 0.48 0 180)
			(size 0.59 0.64)
			(layers "B.Cu" "B.Mask" "B.Paste")
			(roundrect_rratio 0.25)
			(net 7 "+3V3")
			(pintype "passive")
		)
	)
	(footprint "antmicro-footprints:C_0402_1005Metric"
		(layer "B.Cu")
		(at 91.225 102 90)
		(descr "Capacitor SMD 0402")
		(tags "capacitor SMD 0402")
		(property "Reference" "C131"
			(at 9.09 -0.447343 90)
			(layer "B.SilkS")
			(effects
				(font
					(size 0.7 0.7)
					(thickness 0.15)
				)
				(justify right top mirror)
			)
		)
		(property "Value" "C_1u_25V_0402"
			(at -1.022927 -2.155213 90)
			(layer "B.Fab")
			(hide yes)
			(effects
				(font
					(size 0.7 0.7)
					(thickness 0.15)
				)
				(justify right top mirror)
			)
		)
		(property "Datasheet" "https://www.murata.com/products/productdetail?partno=GRM155R61E105KE11%23"
			(at 0 0 90)
			(layer "B.Fab")
			(hide yes)
			(effects
				(font
					(size 1.27 1.27)
					(thickness 0.15)
				)
				(justify mirror)
			)
		)
		(property "Description" "SMD Multilayer Ceramic Capacitor, 1 µF, 25 V, 0402 [1005 Metric], ± 10%, X5R, GRM Series"
			(at 0 0 90)
			(layer "B.Fab")
			(hide yes)
			(effects
				(font
					(size 1.27 1.27)
					(thickness 0.15)
				)
				(justify mirror)
			)
		)
		(property "MPN" "GRM155R61E105KE11J"
			(at 0 0 90)
			(unlocked yes)
			(layer "B.Fab")
			(hide yes)
			(effects
				(font
					(size 1 1)
					(thickness 0.15)
				)
				(justify mirror)
			)
		)
		(property "Manufacturer" "Murata"
			(at 0 0 90)
			(unlocked yes)
			(layer "B.Fab")
			(hide yes)
			(effects
				(font
					(size 1 1)
					(thickness 0.15)
				)
				(justify mirror)
			)
		)
		(property "License" "Apache-2.0"
			(at 0 0 90)
			(unlocked yes)
			(layer "B.Fab")
			(hide yes)
			(effects
				(font
					(size 1 1)
					(thickness 0.15)
				)
				(justify mirror)
			)
		)
		(property "Author" "Antmicro"
			(at 0 0 90)
			(unlocked yes)
			(layer "B.Fab")
			(hide yes)
			(effects
				(font
					(size 1 1)
					(thickness 0.15)
				)
				(justify mirror)
			)
		)
		(property "Val" "1u"
			(at 0 0 90)
			(unlocked yes)
			(layer "B.Fab")
			(hide yes)
			(effects
				(font
					(size 1 1)
					(thickness 0.15)
				)
				(justify mirror)
			)
		)
		(property "Voltage" "25V"
			(at 0 0 90)
			(unlocked yes)
			(layer "B.Fab")
			(hide yes)
			(effects
				(font
					(size 1 1)
					(thickness 0.15)
				)
				(justify mirror)
			)
		)
		(property "Dielectric" "X5R"
			(at 0 0 90)
			(unlocked yes)
			(layer "B.Fab")
			(hide yes)
			(effects
				(font
					(size 1 1)
					(thickness 0.15)
				)
				(justify mirror)
			)
		)
		(sheetname "/X710-AT2 power/")
		(sheetfile "x710-at2-power.kicad_sch")
		(attr smd)
		(fp_rect
			(start -0.925 0.47)
			(end 0.925 -0.47)
			(stroke
				(width 0.05)
				(type default)
			)
			(fill no)
			(layer "B.CrtYd")
		)
		(fp_line
			(start 0.504 -0.248)
			(end -0.494 -0.248)
			(stroke
				(width 0.15)
				(type solid)
			)
			(layer "B.Fab")
		)
		(fp_line
			(start -0.494 -0.248)
			(end -0.494 0.25)
			(stroke
				(width 0.15)
				(type solid)
			)
			(layer "B.Fab")
		)
		(fp_line
			(start 0.504 0.25)
			(end 0.504 -0.248)
			(stroke
				(width 0.15)
				(type solid)
			)
			(layer "B.Fab")
		)
		(fp_line
			(start -0.494 0.25)
			(end 0.504 0.25)
			(stroke
				(width 0.15)
				(type solid)
			)
			(layer "B.Fab")
		)
		(pad "1" smd roundrect
			(at -0.48 0 90)
			(size 0.59 0.64)
			(layers "B.Cu" "B.Mask" "B.Paste")
			(roundrect_rratio 0.25)
			(net 28 "GND")
			(pintype "passive")
		)
		(pad "2" smd roundrect
			(at 0.48 0 90)
			(size 0.59 0.64)
			(layers "B.Cu" "B.Mask" "B.Paste")
			(roundrect_rratio 0.25)
			(net 7 "+3V3")
			(pintype "passive")
		)
	)
)
